# BASEBOARD_FAB2 (Tioga Pass) — schematic netlist excerpt (pin names and nets, part order shuffled) for the footprints in the layout excerpt that follows; sources: Cadence DE-HDL packaged netlist, KiCad conversion of Wiwynn_Tioga_Pass_MB.brd

C6B11  CAP  0.22UF 16V 10% X7R  pkg 0402  page 105 : A = P3E_CPU0_PE1_PCH_TXN<12> ; B = P3E_CPU0_PE1_PCH_C_TXN<12>
L7A2  IND-300NH-20-GP  pkg DISCRET-GB1  page 236 : S = VR_PVNN_PCH_PH1_PHASE_SW ; F = PVNN_PCH_STBY
R25W68  RES  33.2 1% CHIP  pkg 0402  page 146 : A = LPC_LAD3_IO3 ; B = LPC_LAD3_IO3_R

(kicad_pcb
	(version 20260206)
	(generator "pcbnew")
	(generator_version "10.0")
	(general
		(thickness 1.6)
		(legacy_teardrops no)
	)
	(paper "A4")
	(title_block
		(title "Wiwynn_Tioga_Pass_MB.brd")
		(comment 1 "Tioga Pass / footprints 2287-2289 of 4770")
	)
	(layers
		(0 "F.Cu" signal "TOP")
		(4 "In1.Cu" signal "L2GND")
		(6 "In2.Cu" signal "L3")
		(8 "In3.Cu" signal "L4GND")
		(10 "In4.Cu" signal "L5")
		(12 "In5.Cu" signal "L6GND")
		(14 "In6.Cu" signal "L7VCC")
		(16 "In7.Cu" signal "L8VCC")
		(18 "In8.Cu" signal "L9GND")
		(20 "In9.Cu" signal "L10")
		(22 "In10.Cu" signal "L11GND")
		(24 "In11.Cu" signal "L12")
		(26 "In12.Cu" signal "L13GND")
		(2 "B.Cu" signal "BOTTOM")
		(9 "F.Adhes" user "F.Adhesive")
		(11 "B.Adhes" user "B.Adhesive")
		(13 "F.Paste" user "Package Geometry/Pastemask Top")
		(15 "B.Paste" user "Package Geometry/Pastemask Bottom")
		(5 "F.SilkS" user "Ref Des/Silkscreen Top")
		(7 "B.SilkS" user "Ref Des/Silkscreen Bottom")
		(1 "F.Mask" user "Board Geometry/Soldermask Top")
		(3 "B.Mask" user "Board Geometry/Soldermask Bottom")
		(17 "Dwgs.User" user "User.Drawings")
		(19 "Cmts.User" user "User.Comments")
		(21 "Eco1.User" user "User.Eco1")
		(23 "Eco2.User" user "User.Eco2")
		(25 "Edge.Cuts" user "Board Geometry/Outline")
		(27 "Margin" user)
		(31 "F.CrtYd" user "Package Geometry/Place Bound Top")
		(29 "B.CrtYd" user "Package Geometry/Place Bound Bottom")
		(35 "F.Fab" user "Ref Des/Assembly Top")
		(33 "B.Fab" user "Ref Des/Assembly Bottom")
	)
	(footprint ""
		(layer "F.Cu")
		(at 321.16522 -120.53316 90)
		(property "Reference" "C6B11"
			(at -0.8382 -0.67818 90)
			(unlocked yes)
			(layer "F.SilkS")
			(effects
				(font
					(size 0.4064 0.254)
					(thickness 0.1524)
				)
				(justify left)
			)
		)
		(property "Value" ""
			(at 0 0 90)
			(layer "F.Fab")
			(effects
				(font
					(size 1.27 1.27)
				)
			)
		)
		(duplicate_pad_numbers_are_jumpers no)
		(fp_poly
			(pts
				(xy 0.3048 -0.1016) (xy 0.3048 0.9906) (xy -0.3048 0.9906) (xy -0.3048 -0.1016)
			)
			(stroke
				(width 0)
				(type default)
			)
			(fill no)
			(layer "F.CrtYd")
		)
		(fp_line
			(start 0.3048 -0.1016)
			(end -0.3048 -0.1016)
			(stroke
				(width 0.1)
				(type default)
			)
			(layer "F.Fab")
		)
		(fp_line
			(start -0.3048 -0.1016)
			(end -0.3048 0.9906)
			(stroke
				(width 0.1)
				(type default)
			)
			(layer "F.Fab")
		)
		(fp_line
			(start 0.3048 0.9906)
			(end 0.3048 -0.1016)
			(stroke
				(width 0.1)
				(type default)
			)
			(layer "F.Fab")
		)
		(fp_line
			(start -0.3048 0.9906)
			(end 0.3048 0.9906)
			(stroke
				(width 0.1)
				(type default)
			)
			(layer "F.Fab")
		)
		(pad "1" smd rect
			(at 0 0 90)
			(size 0.508 0.508)
			(layers "F.Cu" "F.Mask" "F.Paste")
			(net "P3E_CPU0_PE1_PCH_TXN<12>")
		)
		(pad "2" smd rect
			(at 0 0.889 90)
			(size 0.508 0.508)
			(layers "F.Cu" "F.Mask" "F.Paste")
			(net "P3E_CPU0_PE1_PCH_C_TXN<12>")
		)
		(zone
			(layer "F.Cu")
			(hatch none 0.5)
			(connect_pads
				(clearance 0)
			)
			(min_thickness 0.25)
			(keepout
				(tracks allowed)
				(vias not_allowed)
				(pads allowed)
				(copperpour not_allowed)
				(footprints allowed)
			)
			(placement
				(enabled no)
				(sheetname "")
			)
			(fill
				(thermal_gap 0.5)
				(thermal_bridge_width 0.5)
				(island_removal_mode 0)
			)
			(polygon
				(pts
					(xy 321.41922 -120.27916) (xy 321.41922 -120.78716) (xy 321.80022 -120.78716) (xy 321.80022 -120.27916)
				)
			)
		)
		(zone
			(layer "F.Cu")
			(hatch none 0.5)
			(connect_pads
				(clearance 0)
			)
			(min_thickness 0.25)
			(keepout
				(tracks not_allowed)
				(vias allowed)
				(pads allowed)
				(copperpour not_allowed)
				(footprints allowed)
			)
			(placement
				(enabled no)
				(sheetname "")
			)
			(fill
				(thermal_gap 0.5)
				(thermal_bridge_width 0.5)
				(island_removal_mode 0)
			)
			(polygon
				(pts
					(xy 321.80022 -120.27916) (xy 321.80022 -120.78716) (xy 321.41922 -120.78716) (xy 321.41922 -120.27916)
				)
			)
		)
	)
	(footprint ""
		(layer "F.Cu")
		(at 376.3772 -147.8788 -90)
		(property "Reference" "L7A2"
			(at 3.378708 -4.251706 270)
			(unlocked yes)
			(layer "F.SilkS")
			(effects
				(font
					(size 0.4064 0.254)
					(thickness 0.1524)
				)
			)
		)
		(property "Value" ""
			(at 0 0 270)
			(layer "F.Fab")
			(effects
				(font
					(size 1.27 1.27)
				)
			)
		)
		(duplicate_pad_numbers_are_jumpers no)
		(fp_line
			(start -1.1303 3.199892)
			(end -1.1303 1.6637)
			(stroke
				(width 0.1524)
				(type default)
			)
			(layer "F.SilkS")
		)
		(fp_line
			(start 8.3693 3.199892)
			(end -1.1303 3.199892)
			(stroke
				(width 0.1524)
				(type default)
			)
			(layer "F.SilkS")
		)
		(fp_line
			(start 8.3693 1.6637)
			(end 8.3693 3.199892)
			(stroke
				(width 0.1524)
				(type default)
			)
			(layer "F.SilkS")
		)
		(fp_line
			(start -1.1303 -1.6637)
			(end -1.1303 -3.199892)
			(stroke
				(width 0.1524)
				(type default)
			)
			(layer "F.SilkS")
		)
		(fp_line
			(start -1.1303 -3.199892)
			(end 8.3693 -3.199892)
			(stroke
				(width 0.1524)
				(type default)
			)
			(layer "F.SilkS")
		)
		(fp_line
			(start 8.3693 -3.199892)
			(end 8.3693 -1.6637)
			(stroke
				(width 0.1524)
				(type default)
			)
			(layer "F.SilkS")
		)
		(fp_rect
			(start -1.1303 3.199892)
			(end 8.3693 -3.199892)
			(stroke
				(width 0)
				(type default)
			)
			(fill no)
			(layer "F.CrtYd")
		)
		(fp_line
			(start -1.1303 3.199892)
			(end -1.1303 -3.199892)
			(stroke
				(width 0.1)
				(type default)
			)
			(layer "F.Fab")
		)
		(fp_line
			(start 8.3693 3.199892)
			(end -1.1303 3.199892)
			(stroke
				(width 0.1)
				(type default)
			)
			(layer "F.Fab")
		)
		(fp_line
			(start -1.1303 -3.199892)
			(end 8.3693 -3.199892)
			(stroke
				(width 0.1)
				(type default)
			)
			(layer "F.Fab")
		)
		(fp_line
			(start 8.3693 -3.199892)
			(end 8.3693 3.199892)
			(stroke
				(width 0.1)
				(type default)
			)
			(layer "F.Fab")
		)
		(pad "1" smd rect
			(at 0 0 270)
			(size 3.683 2.667)
			(layers "F.Cu" "F.Mask" "F.Paste")
			(net "VR_PVNN_PCH_PH1_PHASE_SW")
		)
		(pad "2" smd rect
			(at 7.239 0 270)
			(size 3.683 2.667)
			(layers "F.Cu" "F.Mask" "F.Paste")
			(net "PVNN_PCH_STBY")
		)
	)
	(footprint ""
		(layer "F.Cu")
		(at 380.746 -88.2015)
		(property "Reference" "R25W68"
			(at -0.8382 -0.67818 0)
			(unlocked yes)
			(layer "F.SilkS")
			(effects
				(font
					(size 0.4064 0.254)
					(thickness 0.1524)
				)
				(justify left)
			)
		)
		(property "Value" ""
			(at 0 0 0)
			(layer "F.Fab")
			(effects
				(font
					(size 1.27 1.27)
				)
			)
		)
		(duplicate_pad_numbers_are_jumpers no)
		(fp_poly
			(pts
				(xy -0.2794 -0.1016) (xy 0.2794 -0.1016) (xy 0.2794 0.9906) (xy -0.2794 0.9906)
			)
			(stroke
				(width 0)
				(type default)
			)
			(fill no)
			(layer "F.CrtYd")
		)
		(fp_line
			(start -0.2794 -0.1016)
			(end -0.2794 0.9906)
			(stroke
				(width 0.1)
				(type default)
			)
			(layer "F.Fab")
		)
		(fp_line
			(start -0.2794 0.9906)
			(end 0.2794 0.9906)
			(stroke
				(width 0.1)
				(type default)
			)
			(layer "F.Fab")
		)
		(fp_line
			(start 0.2794 -0.1016)
			(end -0.2794 -0.1016)
			(stroke
				(width 0.1)
				(type default)
			)
			(layer "F.Fab")
		)
		(fp_line
			(start 0.2794 0.9906)
			(end 0.2794 -0.1016)
			(stroke
				(width 0.1)
				(type default)
			)
			(layer "F.Fab")
		)
		(pad "1" smd rect
			(at 0 0)
			(size 0.508 0.508)
			(layers "F.Cu" "F.Mask" "F.Paste")
			(net "LPC_LAD3_IO3")
		)
		(pad "2" smd rect
			(at 0 0.889)
			(size 0.508 0.508)
			(layers "F.Cu" "F.Mask" "F.Paste")
			(net "LPC_LAD3_IO3_R")
		)
		(zone
			(layer "F.Cu")
			(hatch none 0.5)
			(connect_pads
				(clearance 0)
			)
			(min_thickness 0.25)
			(keepout
				(tracks allowed)
				(vias not_allowed)
				(pads allowed)
				(copperpour not_allowed)
				(footprints allowed)
			)
			(placement
				(enabled no)
				(sheetname "")
			)
			(fill
				(thermal_gap 0.5)
				(thermal_bridge_width 0.5)
				(island_removal_mode 0)
			)
			(polygon
				(pts
					(xy 380.492 -87.9475) (xy 381 -87.9475) (xy 381 -87.5665) (xy 380.492 -87.5665)
				)
			)
		)
		(zone
			(layer "F.Cu")
			(hatch none 0.5)
			(connect_pads
				(clearance 0)
			)
			(min_thickness 0.25)
			(keepout
				(tracks not_allowed)
				(vias allowed)
				(pads allowed)
				(copperpour not_allowed)
				(footprints allowed)
			)
			(placement
				(enabled no)
				(sheetname "")
			)
			(fill
				(thermal_gap 0.5)
				(thermal_bridge_width 0.5)
				(island_removal_mode 0)
			)
			(polygon
				(pts
					(xy 380.492 -87.5665) (xy 381 -87.5665) (xy 381 -87.9475) (xy 380.492 -87.9475)
				)
			)
		)
	)
)
